(kicad_pcb
	(version 20241229)
	(generator "pcbnew")
	(generator_version "9.0")
	(general
		(thickness 1.711)
		(legacy_teardrops no)
	)
	(paper "A4")
	(title_block
		(title "Antmicro Baseboard for Jetson AGX Thor")
		(date "2026-02-18")
		(rev "1.1.0")
		(company "Antmicro Ltd")
		(comment 1 "www.antmicro.com")
		(comment 9 "footprints 1117-1118 of 1170")
	)
	(layers
		(0 "F.Cu" signal)
		(4 "In1.Cu" signal)
		(6 "In2.Cu" signal)
		(8 "In3.Cu" signal)
		(10 "In4.Cu" jumper)
		(12 "In5.Cu" signal)
		(14 "In6.Cu" signal)
		(16 "In7.Cu" signal)
		(18 "In8.Cu" signal)
		(2 "B.Cu" signal)
		(9 "F.Adhes" user "F.Adhesive")
		(11 "B.Adhes" user "B.Adhesive")
		(13 "F.Paste" user)
		(15 "B.Paste" user)
		(5 "F.SilkS" user "F.Silkscreen")
		(7 "B.SilkS" user "B.Silkscreen")
		(1 "F.Mask" user)
		(3 "B.Mask" user)
		(17 "Dwgs.User" user "User.Drawings")
		(19 "Cmts.User" user "User.Comments")
		(21 "Eco1.User" user "User.Eco1")
		(23 "Eco2.User" user "User.Eco2")
		(25 "Edge.Cuts" user)
		(27 "Margin" user)
		(31 "F.CrtYd" user "F.Courtyard")
		(29 "B.CrtYd" user "B.Courtyard")
		(35 "F.Fab" user)
		(33 "B.Fab" user)
	)
	(footprint "antmicro-footprints:Conn_FFC_WE_68715014x22"
		(locked yes)
		(layer "B.Cu")
		(at 205.908 56.24)
		(property "Reference" "J10"
			(at -15.181 2.976 0)
			(layer "B.SilkS")
			(effects
				(font
					(size 0.7 0.7)
					(thickness 0.15)
				)
				(justify right top mirror)
			)
		)
		(property "Value" "Conn_FFC_WE_68715014522"
			(at 0 -4.5 0)
			(layer "B.Fab")
			(effects
				(font
					(size 0.7 0.7)
					(thickness 0.15)
				)
				(justify right top mirror)
			)
		)
		(property "Datasheet" "https://www.we-online.com/components/products/datasheet/68715014522.pdf"
			(at 0 0 0)
			(layer "B.Fab")
			(hide yes)
			(effects
				(font
					(size 1.27 1.27)
					(thickness 0.15)
				)
				(justify mirror)
			)
		)
		(property "Description" "FFC connector"
			(at 0 0 0)
			(layer "B.Fab")
			(hide yes)
			(effects
				(font
					(size 1.27 1.27)
					(thickness 0.15)
				)
				(justify mirror)
			)
		)
		(property "MPN" "68715014522"
			(at 0 0 180)
			(unlocked yes)
			(layer "B.Fab")
			(hide yes)
			(effects
				(font
					(size 1 1)
					(thickness 0.15)
				)
				(justify mirror)
			)
		)
		(property "Manufacturer" "Würth Elektronik"
			(at 0 0 180)
			(unlocked yes)
			(layer "B.Fab")
			(hide yes)
			(effects
				(font
					(size 1 1)
					(thickness 0.15)
				)
				(justify mirror)
			)
		)
		(property "Author" "Antmicro"
			(at 0 0 180)
			(unlocked yes)
			(layer "B.Fab")
			(hide yes)
			(effects
				(font
					(size 1 1)
					(thickness 0.15)
				)
				(justify mirror)
			)
		)
		(property "License" "Apache-2.0"
			(at 0 0 180)
			(unlocked yes)
			(layer "B.Fab")
			(hide yes)
			(effects
				(font
					(size 1 1)
					(thickness 0.15)
				)
				(justify mirror)
			)
		)
		(sheetname "/CSI/")
		(sheetfile "csi.kicad_sch")
		(attr smd)
		(fp_line
			(start -15.85 -2.7)
			(end -15.85 2.15)
			(stroke
				(width 0.15)
				(type solid)
			)
			(layer "B.SilkS")
		)
		(fp_line
			(start -15.85 2.15)
			(end -12.5 2.15)
			(stroke
				(width 0.15)
				(type solid)
			)
			(layer "B.SilkS")
		)
		(fp_line
			(start -12.5 2.15)
			(end -12.5 2.976)
			(stroke
				(width 0.15)
				(type solid)
			)
			(layer "B.SilkS")
		)
		(fp_line
			(start -12.5 2.976)
			(end 12.499 2.976)
			(stroke
				(width 0.15)
				(type solid)
			)
			(layer "B.SilkS")
		)
		(fp_line
			(start 12.499 2.15)
			(end 12.499 2.976)
			(stroke
				(width 0.15)
				(type solid)
			)
			(layer "B.SilkS")
		)
		(fp_line
			(start 15.85 -2.7)
			(end -15.85 -2.7)
			(stroke
				(width 0.15)
				(type solid)
			)
			(layer "B.SilkS")
		)
		(fp_line
			(start 15.85 -2.7)
			(end 15.85 2.15)
			(stroke
				(width 0.15)
				(type solid)
			)
			(layer "B.SilkS")
		)
		(fp_line
			(start 15.85 2.15)
			(end 12.499 2.15)
			(stroke
				(width 0.15)
				(type solid)
			)
			(layer "B.SilkS")
		)
		(fp_circle
			(center -12.9 2.9)
			(end -12.85 2.85)
			(stroke
				(width 0.15)
				(type solid)
			)
			(fill yes)
			(layer "B.SilkS")
		)
		(fp_rect
			(start -16.2 3.25)
			(end 16.2 -3.55)
			(stroke
				(width 0.05)
				(type solid)
			)
			(fill no)
			(layer "B.CrtYd")
		)
		(fp_text user "${REFERENCE}"
			(at -16.2 -5.9 0)
			(layer "B.Fab")
			(effects
				(font
					(size 0.7 0.7)
					(thickness 0.15)
				)
				(justify right top mirror)
			)
		)
		(fp_text user "License: Apache-2.0"
			(at -16.2 -7.9 0)
			(layer "B.Fab")
			(effects
				(font
					(size 0.7 0.7)
					(thickness 0.15)
				)
				(justify right top mirror)
			)
		)
		(fp_text user "Author: Antmicro"
			(at -16.2 -6.9 0)
			(layer "B.Fab")
			(effects
				(font
					(size 0.7 0.7)
					(thickness 0.15)
				)
				(justify right top mirror)
			)
		)
		(pad "1" smd roundrect
			(at -12.25 2.15)
			(size 0.3 1.2)
			(layers "B.Cu" "B.Mask" "B.Paste")
			(roundrect_rratio 0.25)
			(net 79 "/CSI/CAM2.CSI5_D1-")
			(pintype "passive")
		)
		(pad "2" smd roundrect
			(at -11.75 2.15)
			(size 0.3 1.2)
			(layers "B.Cu" "B.Mask" "B.Paste")
			(roundrect_rratio 0.25)
			(net 163 "/CSI/CAM2.CSI5_D1+")
			(pintype "passive")
		)
		(pad "3" smd roundrect
			(at -11.25 2.15)
			(size 0.3 1.2)
			(layers "B.Cu" "B.Mask" "B.Paste")
			(roundrect_rratio 0.25)
			(net 128 "/CSI/CAM2.CSI5_D0-")
			(pintype "passive")
		)
		(pad "4" smd roundrect
			(at -10.75 2.15)
			(size 0.3 1.2)
			(layers "B.Cu" "B.Mask" "B.Paste")
			(roundrect_rratio 0.25)
			(net 125 "/CSI/CAM2.CSI5_D0+")
			(pintype "passive")
		)
		(pad "5" smd roundrect
			(at -10.25 2.15)
			(size 0.3 1.2)
			(layers "B.Cu" "B.Mask" "B.Paste")
			(roundrect_rratio 0.25)
			(net 162 "/CSI/CAM2.CSI4_D1-")
			(pintype "passive")
		)
		(pad "6" smd roundrect
			(at -9.75 2.15)
			(size 0.3 1.2)
			(layers "B.Cu" "B.Mask" "B.Paste")
			(roundrect_rratio 0.25)
			(net 87 "/CSI/CAM2.CSI4_D1+")
			(pintype "passive")
		)
		(pad "7" smd roundrect
			(at -9.25 2.15)
			(size 0.3 1.2)
			(layers "B.Cu" "B.Mask" "B.Paste")
			(roundrect_rratio 0.25)
			(net 122 "/CSI/CAM2.CSI4_D0-")
			(pintype "passive")
		)
		(pad "8" smd roundrect
			(at -8.75 2.15)
			(size 0.3 1.2)
			(layers "B.Cu" "B.Mask" "B.Paste")
			(roundrect_rratio 0.25)
			(net 144 "/CSI/CAM2.CSI4_D0+")
			(pintype "passive")
		)
		(pad "9" smd roundrect
			(at -8.25 2.15)
			(size 0.3 1.2)
			(layers "B.Cu" "B.Mask" "B.Paste")
			(roundrect_rratio 0.25)
			(net 1 "GND")
			(pintype "passive")
		)
		(pad "10" smd roundrect
			(at -7.75 2.15)
			(size 0.3 1.2)
			(layers "B.Cu" "B.Mask" "B.Paste")
			(roundrect_rratio 0.25)
			(net 84 "/CSI/CAM2.CSI4_CLK-")
			(pintype "passive")
		)
		(pad "11" smd roundrect
			(at -7.25 2.15)
			(size 0.3 1.2)
			(layers "B.Cu" "B.Mask" "B.Paste")
			(roundrect_rratio 0.25)
			(net 160 "/CSI/CAM2.CSI4_CLK+")
			(pintype "passive")
		)
		(pad "12" smd roundrect
			(at -6.75 2.15)
			(size 0.3 1.2)
			(layers "B.Cu" "B.Mask" "B.Paste")
			(roundrect_rratio 0.25)
			(net 1 "GND")
			(pintype "passive")
		)
		(pad "13" smd roundrect
			(at -6.25 2.15)
			(size 0.3 1.2)
			(layers "B.Cu" "B.Mask" "B.Paste")
			(roundrect_rratio 0.25)
			(net 181 "unconnected-(J10-Pad13)")
			(pintype "passive+no_connect")
		)
		(pad "14" smd roundrect
			(at -5.75 2.15)
			(size 0.3 1.2)
			(layers "B.Cu" "B.Mask" "B.Paste")
			(roundrect_rratio 0.25)
			(net 183 "unconnected-(J10-Pad14)")
			(pintype "passive+no_connect")
		)
		(pad "15" smd roundrect
			(at -5.25 2.15)
			(size 0.3 1.2)
			(layers "B.Cu" "B.Mask" "B.Paste")
			(roundrect_rratio 0.25)
			(net 1 "GND")
			(pintype "passive")
		)
		(pad "16" smd roundrect
			(at -4.75 2.15)
			(size 0.3 1.2)
			(layers "B.Cu" "B.Mask" "B.Paste")
			(roundrect_rratio 0.25)
			(net 180 "unconnected-(J10-Pad16)")
			(pintype "passive+no_connect")
		)
		(pad "17" smd roundrect
			(at -4.25 2.15)
			(size 0.3 1.2)
			(layers "B.Cu" "B.Mask" "B.Paste")
			(roundrect_rratio 0.25)
			(net 184 "unconnected-(J10-Pad17)")
			(pintype "passive+no_connect")
		)
		(pad "18" smd roundrect
			(at -3.75 2.15)
			(size 0.3 1.2)
			(layers "B.Cu" "B.Mask" "B.Paste")
			(roundrect_rratio 0.25)
			(net 1 "GND")
			(pintype "passive")
		)
		(pad "19" smd roundrect
			(at -3.25 2.15)
			(size 0.3 1.2)
			(layers "B.Cu" "B.Mask" "B.Paste")
			(roundrect_rratio 0.25)
			(net 86 "/CSI/CAM3.CSI7_D1-")
			(pintype "passive")
		)
		(pad "20" smd roundrect
			(at -2.75 2.15)
			(size 0.3 1.2)
			(layers "B.Cu" "B.Mask" "B.Paste")
			(roundrect_rratio 0.25)
			(net 102 "/CSI/CAM3.CSI7_D1+")
			(pintype "passive")
		)
		(pad "21" smd roundrect
			(at -2.25 2.15)
			(size 0.3 1.2)
			(layers "B.Cu" "B.Mask" "B.Paste")
			(roundrect_rratio 0.25)
			(net 59 "/CSI/CAM3.CSI7_D0-")
			(pintype "passive")
		)
		(pad "22" smd roundrect
			(at -1.75 2.15)
			(size 0.3 1.2)
			(layers "B.Cu" "B.Mask" "B.Paste")
			(roundrect_rratio 0.25)
			(net 124 "/CSI/CAM3.CSI7_D0+")
			(pintype "passive")
		)
		(pad "23" smd roundrect
			(at -1.25 2.15)
			(size 0.3 1.2)
			(layers "B.Cu" "B.Mask" "B.Paste")
			(roundrect_rratio 0.25)
			(net 62 "/CSI/CAM3.CSI6_D1-")
			(pintype "passive")
		)
		(pad "24" smd roundrect
			(at -0.75 2.15)
			(size 0.3 1.2)
			(layers "B.Cu" "B.Mask" "B.Paste")
			(roundrect_rratio 0.25)
			(net 70 "/CSI/CAM3.CSI6_D1+")
			(pintype "passive")
		)
		(pad "25" smd roundrect
			(at -0.25 2.15)
			(size 0.3 1.2)
			(layers "B.Cu" "B.Mask" "B.Paste")
			(roundrect_rratio 0.25)
			(net 135 "/CSI/CAM3.CSI6_D0-")
			(pintype "passive")
		)
		(pad "26" smd roundrect
			(at 0.248 2.15)
			(size 0.3 1.2)
			(layers "B.Cu" "B.Mask" "B.Paste")
			(roundrect_rratio 0.25)
			(net 152 "/CSI/CAM3.CSI6_D0+")
			(pintype "passive")
		)
		(pad "27" smd roundrect
			(at 0.748 2.15)
			(size 0.3 1.2)
			(layers "B.Cu" "B.Mask" "B.Paste")
			(roundrect_rratio 0.25)
			(net 1 "GND")
			(pintype "passive")
		)
		(pad "28" smd roundrect
			(at 1.249 2.15)
			(size 0.3 1.2)
			(layers "B.Cu" "B.Mask" "B.Paste")
			(roundrect_rratio 0.25)
			(net 116 "/CSI/CAM3.CSI6_CLK-")
			(pintype "passive")
		)
		(pad "29" smd roundrect
			(at 1.749 2.15)
			(size 0.3 1.2)
			(layers "B.Cu" "B.Mask" "B.Paste")
			(roundrect_rratio 0.25)
			(net 53 "/CSI/CAM3.CSI6_CLK+")
			(pintype "passive")
		)
		(pad "30" smd roundrect
			(at 2.249 2.15)
			(size 0.3 1.2)
			(layers "B.Cu" "B.Mask" "B.Paste")
			(roundrect_rratio 0.25)
			(net 1 "GND")
			(pintype "passive")
		)
		(pad "31" smd roundrect
			(at 2.749 2.15)
			(size 0.3 1.2)
			(layers "B.Cu" "B.Mask" "B.Paste")
			(roundrect_rratio 0.25)
			(net 185 "unconnected-(J10-Pad31)")
			(pintype "passive+no_connect")
		)
		(pad "32" smd roundrect
			(at 3.249 2.15)
			(size 0.3 1.2)
			(layers "B.Cu" "B.Mask" "B.Paste")
			(roundrect_rratio 0.25)
			(net 201 "/CSI/VSYNC_CAM2_3V3")
			(pintype "passive")
		)
		(pad "33" smd roundrect
			(at 3.749 2.15)
			(size 0.3 1.2)
			(layers "B.Cu" "B.Mask" "B.Paste")
			(roundrect_rratio 0.25)
			(net 191 "unconnected-(J10-Pad33)")
			(pintype "passive+no_connect")
		)
		(pad "34" smd roundrect
			(at 4.248 2.15)
			(size 0.3 1.2)
			(layers "B.Cu" "B.Mask" "B.Paste")
			(roundrect_rratio 0.25)
			(net 210 "/CSI/VSYNC_CAM3_3V3")
			(pintype "passive")
		)
		(pad "35" smd roundrect
			(at 4.748 2.15)
			(size 0.3 1.2)
			(layers "B.Cu" "B.Mask" "B.Paste")
			(roundrect_rratio 0.25)
			(net 190 "unconnected-(J10-Pad35)")
			(pintype "passive+no_connect")
		)
		(pad "36" smd roundrect
			(at 5.248 2.15)
			(size 0.3 1.2)
			(layers "B.Cu" "B.Mask" "B.Paste")
			(roundrect_rratio 0.25)
			(net 188 "unconnected-(J10-Pad36)")
			(pintype "passive+no_connect")
		)
		(pad "37" smd roundrect
			(at 5.749 2.15)
			(size 0.3 1.2)
			(layers "B.Cu" "B.Mask" "B.Paste")
			(roundrect_rratio 0.25)
			(net 187 "unconnected-(J10-Pad37)")
			(pintype "passive+no_connect")
		)
		(pad "38" smd roundrect
			(at 6.249 2.15)
			(size 0.3 1.2)
			(layers "B.Cu" "B.Mask" "B.Paste")
			(roundrect_rratio 0.25)
			(net 189 "unconnected-(J10-Pad38)")
			(pintype "passive+no_connect")
		)
		(pad "39" smd roundrect
			(at 6.749 2.15)
			(size 0.3 1.2)
			(layers "B.Cu" "B.Mask" "B.Paste")
			(roundrect_rratio 0.25)
			(net 1373 "Net-(J10-Pad39)")
			(pintype "passive")
		)
		(pad "40" smd roundrect
			(at 7.249 2.15)
			(size 0.3 1.2)
			(layers "B.Cu" "B.Mask" "B.Paste")
			(roundrect_rratio 0.25)
			(net 1372 "Net-(J10-Pad40)")
			(pintype "passive")
		)
		(pad "41" smd roundrect
			(at 7.749 2.15)
			(size 0.3 1.2)
			(layers "B.Cu" "B.Mask" "B.Paste")
			(roundrect_rratio 0.25)
			(net 937 "Net-(J10-Pad41)")
			(pintype "passive")
		)
		(pad "42" smd roundrect
			(at 8.249 2.15)
			(size 0.3 1.2)
			(layers "B.Cu" "B.Mask" "B.Paste")
			(roundrect_rratio 0.25)
			(net 938 "Net-(J10-Pad42)")
			(pintype "passive")
		)
		(pad "43" smd roundrect
			(at 8.749 2.15)
			(size 0.3 1.2)
			(layers "B.Cu" "B.Mask" "B.Paste")
			(roundrect_rratio 0.25)
			(net 193 "unconnected-(J10-Pad43)")
			(pintype "passive+no_connect")
		)
		(pad "44" smd roundrect
			(at 9.249 2.15)
			(size 0.3 1.2)
			(layers "B.Cu" "B.Mask" "B.Paste")
			(roundrect_rratio 0.25)
			(net 195 "unconnected-(J10-Pad44)")
			(pintype "passive+no_connect")
		)
		(pad "45" smd roundrect
			(at 9.749 2.15)
			(size 0.3 1.2)
			(layers "B.Cu" "B.Mask" "B.Paste")
			(roundrect_rratio 0.25)
			(net 192 "unconnected-(J10-Pad45)")
			(pintype "passive+no_connect")
		)
		(pad "46" smd roundrect
			(at 10.249 2.15)
			(size 0.3 1.2)
			(layers "B.Cu" "B.Mask" "B.Paste")
			(roundrect_rratio 0.25)
			(net 182 "unconnected-(J10-Pad46)")
			(pintype "passive+no_connect")
		)
		(pad "47" smd roundrect
			(at 10.749 2.15)
			(size 0.3 1.2)
			(layers "B.Cu" "B.Mask" "B.Paste")
			(roundrect_rratio 0.25)
			(net 8 "/CSI/CSIB_3V3")
			(pintype "passive")
		)
		(pad "48" smd roundrect
			(at 11.249 2.15)
			(size 0.3 1.2)
			(layers "B.Cu" "B.Mask" "B.Paste")
			(roundrect_rratio 0.25)
			(net 8 "/CSI/CSIB_3V3")
			(pintype "passive")
		)
		(pad "49" smd roundrect
			(at 11.749 2.15)
			(size 0.3 1.2)
			(layers "B.Cu" "B.Mask" "B.Paste")
			(roundrect_rratio 0.25)
			(net 9 "/CSI/CSIB_5V")
			(pintype "passive")
		)
		(pad "50" smd roundrect
			(at 12.249 2.15)
			(size 0.3 1.2)
			(layers "B.Cu" "B.Mask" "B.Paste")
			(roundrect_rratio 0.25)
			(net 9 "/CSI/CSIB_5V")
			(pintype "passive")
		)
		(pad "MP1" smd roundrect
			(at -14.198 0.3)
			(size 2.7 3)
			(layers "B.Cu" "B.Mask" "B.Paste")
			(roundrect_rratio 0.05)
			(net 1 "GND")
			(pinfunction "MP")
			(pintype "passive")
		)
		(pad "MP2" smd roundrect
			(at 14.198 0.3)
			(size 2.7 3)
			(layers "B.Cu" "B.Mask" "B.Paste")
			(roundrect_rratio 0.05)
			(net 1 "GND")
			(pinfunction "MP")
			(pintype "passive")
		)
	)
	(footprint "antmicro-footprints:C_0402_1005Metric"
		(layer "B.Cu")
		(at 90.780001 105.5 -90)
		(descr "Capacitor SMD 0402")
		(tags "capacitor SMD 0402")
		(property "Reference" "C325"
			(at 1 -0.5 90)
			(layer "B.SilkS")
			(effects
				(font
					(size 0.7 0.7)
					(thickness 0.15)
				)
				(justify left bottom mirror)
			)
		)
		(property "Value" "C_100n_0402"
			(at -1.022927 -2.155213 90)
			(layer "B.Fab")
			(effects
				(font
					(size 0.7 0.7)
					(thickness 0.15)
				)
				(justify left bottom mirror)
			)
		)
		(property "Datasheet" "https://www.murata.com/products/productdetail?partno=GRM155R61H104KE14%23"
			(at 0 0 90)
			(layer "B.Fab")
			(hide yes)
			(effects
				(font
					(size 1.27 1.27)
					(thickness 0.15)
				)
				(justify mirror)
			)
		)
		(property "Description" "SMD Multilayer Ceramic Capacitor, 0.1 µF, 50 V, 0402 [1005 Metric], ± 10%, X5R, GRM Series"
			(at 0 0 90)
			(layer "B.Fab")
			(hide yes)
			(effects
				(font
					(size 1.27 1.27)
					(thickness 0.15)
				)
				(justify mirror)
			)
		)
		(property "Manufacturer" "Murata"
			(at 0 0 90)
			(unlocked yes)
			(layer "B.Fab")
			(hide yes)
			(effects
				(font
					(size 1 1)
					(thickness 0.15)
				)
				(justify mirror)
			)
		)
		(property "MPN" "GRM155R61H104KE14D"
			(at 0 0 90)
			(unlocked yes)
			(layer "B.Fab")
			(hide yes)
			(effects
				(font
					(size 1 1)
					(thickness 0.15)
				)
				(justify mirror)
			)
		)
		(property "Val" "100n"
			(at 0 0 90)
			(unlocked yes)
			(layer "B.Fab")
			(hide yes)
			(effects
				(font
					(size 1 1)
					(thickness 0.15)
				)
				(justify mirror)
			)
		)
		(property "License" "Apache-2.0"
			(at 0 0 90)
			(unlocked yes)
			(layer "B.Fab")
			(hide yes)
			(effects
				(font
					(size 1 1)
					(thickness 0.15)
				)
				(justify mirror)
			)
		)
		(property "Author" "Antmicro"
			(at 0 0 90)
			(unlocked yes)
			(layer "B.Fab")
			(hide yes)
			(effects
				(font
					(size 1 1)
					(thickness 0.15)
				)
				(justify mirror)
			)
		)
		(property "Voltage" "50V"
			(at 0 0 90)
			(unlocked yes)
			(layer "B.Fab")
			(hide yes)
			(effects
				(font
					(size 1 1)
					(thickness 0.15)
				)
				(justify mirror)
			)
		)
		(property "Dielectric" "X5R"
			(at 0 0 90)
			(unlocked yes)
			(layer "B.Fab")
			(hide yes)
			(effects
				(font
					(size 1 1)
					(thickness 0.15)
				)
				(justify mirror)
			)
		)
		(sheetname "/SoM_IO2/")
		(sheetfile "som_io2.kicad_sch")
		(attr smd)
		(fp_poly
			(pts
				(xy -0.925 0.47) (xy 0.925 0.47) (xy 0.925 -0.47) (xy -0.925 -0.47)
			)
			(stroke
				(width 0.05)
				(type default)
			)
			(fill no)
			(layer "B.CrtYd")
		)
		(fp_line
			(start -0.494 0.25)
			(end 0.504 0.25)
			(stroke
				(width 0.15)
				(type solid)
			)
			(layer "B.Fab")
		)
		(fp_line
			(start 0.504 0.25)
			(end 0.504 -0.248)
			(stroke
				(width 0.15)
				(type solid)
			)
			(layer "B.Fab")
		)
		(fp_line
			(start -0.494 -0.248)
			(end -0.494 0.25)
			(stroke
				(width 0.15)
				(type solid)
			)
			(layer "B.Fab")
		)
		(fp_line
			(start 0.504 -0.248)
			(end -0.494 -0.248)
			(stroke
				(width 0.15)
				(type solid)
			)
			(layer "B.Fab")
		)
		(fp_text user "${REFERENCE}"
			(at -0.939 -4.599 90)
			(layer "B.Fab")
			(effects
				(font
					(size 0.7 0.7)
					(thickness 0.15)
				)
				(justify left bottom mirror)
			)
		)
		(fp_text user "License: Apache-2.0"
			(at -0.939 -5.799 90)
			(layer "B.Fab")
			(effects
				(font
					(size 0.7 0.7)
					(thickness 0.15)
				)
				(justify left bottom mirror)
			)
		)
		(fp_text user "Author: Antmicro"
			(at -0.939 -3.399 90)
			(layer "B.Fab")
			(effects
				(font
					(size 0.7 0.7)
					(thickness 0.15)
				)
				(justify left bottom mirror)
			)
		)
		(pad "1" smd roundrect
			(at -0.48 0 270)
			(size 0.59 0.64)
			(layers "B.Cu" "B.Mask" "B.Paste")
			(roundrect_rratio 0.25)
			(net 771 "/Expansion connector/DP1.TX1+")
			(pintype "passive")
		)
		(pad "2" smd roundrect
			(at 0.48 0 270)
			(size 0.59 0.64)
			(layers "B.Cu" "B.Mask" "B.Paste")
			(roundrect_rratio 0.25)
			(net 1209 "/SoM_IO2/DP1.TX1_C+")
			(pintype "passive")
		)
	)
)
